(kicad_pcb
	(version 20260206)
	(generator "pcbnew")
	(generator_version "10.0")
	(general
		(thickness 1.6)
		(legacy_teardrops no)
	)
	(paper "A4")
	(title_block
		(title "9054_F0T_PDB_BD_GPU_F_V04_1213_1550_OCP.brd")
		(comment 1 "Grand Teton / footprints 254-260 of 608")
	)
	(layers
		(0 "F.Cu" signal "TOP")
		(4 "In1.Cu" signal "GND")
		(6 "In2.Cu" signal "IN1")
		(8 "In3.Cu" signal "GND1")
		(10 "In4.Cu" signal "VCC")
		(12 "In5.Cu" signal "VCC1")
		(14 "In6.Cu" signal "GND2")
		(16 "In7.Cu" signal "IN2")
		(18 "In8.Cu" signal "GND3")
		(2 "B.Cu" signal "BOTTOM")
		(9 "F.Adhes" user "F.Adhesive")
		(11 "B.Adhes" user "B.Adhesive")
		(13 "F.Paste" user "Package Geometry/Pastemask Top")
		(15 "B.Paste" user "Package Geometry/Pastemask Bottom")
		(5 "F.SilkS" user "Ref Des/Silkscreen Top")
		(7 "B.SilkS" user "Ref Des/Silkscreen Bottom")
		(1 "F.Mask" user "Board Geometry/Soldermask Top")
		(3 "B.Mask" user "Board Geometry/Soldermask Bottom")
		(17 "Dwgs.User" user "User.Drawings")
		(19 "Cmts.User" user "User.Comments")
		(21 "Eco1.User" user "User.Eco1")
		(23 "Eco2.User" user "User.Eco2")
		(25 "Edge.Cuts" user "Board Geometry/Outline")
		(27 "Margin" user)
		(31 "F.CrtYd" user "Package Geometry/Place Bound Top")
		(29 "B.CrtYd" user "Package Geometry/Place Bound Bottom")
		(35 "F.Fab" user "Ref Des/Assembly Top")
		(33 "B.Fab" user "Ref Des/Assembly Bottom")
	)
	(footprint ""
		(layer "F.Cu")
		(at 304.546 -73.279)
		(property "Reference" "PR7040"
			(at 0 0 0)
			(layer "F.SilkS")
			(hide yes)
			(effects
				(font
					(size 1.27 1.27)
				)
			)
		)
		(property "Value" ""
			(at 0 0 0)
			(layer "F.Fab")
			(effects
				(font
					(size 1.27 1.27)
				)
			)
		)
		(duplicate_pad_numbers_are_jumpers no)
		(fp_line
			(start -0.7874 -0.4064)
			(end 0.7874 -0.4064)
			(stroke
				(width 0.1524)
				(type default)
			)
			(layer "F.SilkS")
		)
		(fp_line
			(start -0.7874 0.4064)
			(end -0.7874 -0.4064)
			(stroke
				(width 0.1524)
				(type default)
			)
			(layer "F.SilkS")
		)
		(fp_line
			(start 0.7874 -0.4064)
			(end 0.7874 0.4064)
			(stroke
				(width 0.1524)
				(type default)
			)
			(layer "F.SilkS")
		)
		(fp_line
			(start 0.7874 0.4064)
			(end -0.7874 0.4064)
			(stroke
				(width 0.1524)
				(type default)
			)
			(layer "F.SilkS")
		)
		(fp_line
			(start -0.67945 -0.305054)
			(end -0.12065 -0.305054)
			(stroke
				(width 0.1)
				(type default)
			)
			(layer "F.Fab")
		)
		(fp_line
			(start -0.67945 0.3048)
			(end -0.67945 -0.305054)
			(stroke
				(width 0.1)
				(type default)
			)
			(layer "F.Fab")
		)
		(fp_line
			(start -0.12065 -0.305054)
			(end -0.12065 -0.2794)
			(stroke
				(width 0.1)
				(type default)
			)
			(layer "F.Fab")
		)
		(fp_line
			(start -0.12065 -0.2794)
			(end 0.12065 -0.2794)
			(stroke
				(width 0.1)
				(type default)
			)
			(layer "F.Fab")
		)
		(fp_line
			(start -0.12065 0.2794)
			(end -0.12065 0.3048)
			(stroke
				(width 0.1)
				(type default)
			)
			(layer "F.Fab")
		)
		(fp_line
			(start -0.12065 0.3048)
			(end -0.67945 0.3048)
			(stroke
				(width 0.1)
				(type default)
			)
			(layer "F.Fab")
		)
		(fp_line
			(start 0.120396 0.2794)
			(end -0.12065 0.2794)
			(stroke
				(width 0.1)
				(type default)
			)
			(layer "F.Fab")
		)
		(fp_line
			(start 0.120396 0.3048)
			(end 0.120396 0.2794)
			(stroke
				(width 0.1)
				(type default)
			)
			(layer "F.Fab")
		)
		(fp_line
			(start 0.12065 -0.3048)
			(end 0.67945 -0.3048)
			(stroke
				(width 0.1)
				(type default)
			)
			(layer "F.Fab")
		)
		(fp_line
			(start 0.12065 -0.2794)
			(end 0.12065 -0.3048)
			(stroke
				(width 0.1)
				(type default)
			)
			(layer "F.Fab")
		)
		(fp_line
			(start 0.67945 -0.3048)
			(end 0.67945 0.3048)
			(stroke
				(width 0.1)
				(type default)
			)
			(layer "F.Fab")
		)
		(fp_line
			(start 0.67945 0.3048)
			(end 0.120396 0.3048)
			(stroke
				(width 0.1)
				(type default)
			)
			(layer "F.Fab")
		)
		(pad "1" smd circle
			(at -0.40005 0)
			(size 0 0)
			(layers "F.Cu" "F.Mask" "F.Paste")
			(net "P52V_HS_4287_S1P")
		)
		(pad "2" smd circle
			(at 0.40005 0)
			(size 0 0)
			(layers "F.Cu" "F.Mask" "F.Paste")
			(net "P52V_HS_4287_S1N")
		)
	)
	(footprint ""
		(layer "F.Cu")
		(at 140.79982 -34.3662)
		(property "Reference" "PR6988"
			(at 0 0 0)
			(layer "F.SilkS")
			(hide yes)
			(effects
				(font
					(size 1.27 1.27)
				)
			)
		)
		(property "Value" ""
			(at 0 0 0)
			(layer "F.Fab")
			(effects
				(font
					(size 1.27 1.27)
				)
			)
		)
		(duplicate_pad_numbers_are_jumpers no)
		(fp_line
			(start -1.2954 -0.5842)
			(end 1.2954 -0.5842)
			(stroke
				(width 0.1524)
				(type default)
			)
			(layer "F.SilkS")
		)
		(fp_line
			(start -1.2954 0.5842)
			(end -1.2954 -0.5842)
			(stroke
				(width 0.1524)
				(type default)
			)
			(layer "F.SilkS")
		)
		(fp_line
			(start 1.2954 -0.5842)
			(end 1.2954 0.5842)
			(stroke
				(width 0.1524)
				(type default)
			)
			(layer "F.SilkS")
		)
		(fp_line
			(start 1.2954 0.5842)
			(end -1.2954 0.5842)
			(stroke
				(width 0.1524)
				(type default)
			)
			(layer "F.SilkS")
		)
		(fp_line
			(start -1.1938 -0.406654)
			(end -0.8636 -0.406654)
			(stroke
				(width 0.1)
				(type default)
			)
			(layer "F.Fab")
		)
		(fp_line
			(start -1.1938 0.4064)
			(end -1.1938 -0.406654)
			(stroke
				(width 0.1)
				(type default)
			)
			(layer "F.Fab")
		)
		(fp_line
			(start -0.8636 -0.4572)
			(end 0.8636 -0.4572)
			(stroke
				(width 0.1)
				(type default)
			)
			(layer "F.Fab")
		)
		(fp_line
			(start -0.8636 -0.406654)
			(end -0.8636 -0.4572)
			(stroke
				(width 0.1)
				(type default)
			)
			(layer "F.Fab")
		)
		(fp_line
			(start -0.8636 0.4064)
			(end -1.1938 0.4064)
			(stroke
				(width 0.1)
				(type default)
			)
			(layer "F.Fab")
		)
		(fp_line
			(start -0.8636 0.4318)
			(end -0.8636 0.4064)
			(stroke
				(width 0.1)
				(type default)
			)
			(layer "F.Fab")
		)
		(fp_line
			(start -0.8636 0.4572)
			(end -0.8636 0.4318)
			(stroke
				(width 0.1)
				(type default)
			)
			(layer "F.Fab")
		)
		(fp_line
			(start 0.8636 -0.4572)
			(end 0.8636 -0.406654)
			(stroke
				(width 0.1)
				(type default)
			)
			(layer "F.Fab")
		)
		(fp_line
			(start 0.8636 -0.406654)
			(end 1.1938 -0.406654)
			(stroke
				(width 0.1)
				(type default)
			)
			(layer "F.Fab")
		)
		(fp_line
			(start 0.8636 0.4064)
			(end 0.8636 0.4572)
			(stroke
				(width 0.1)
				(type default)
			)
			(layer "F.Fab")
		)
		(fp_line
			(start 0.8636 0.4572)
			(end -0.8636 0.4572)
			(stroke
				(width 0.1)
				(type default)
			)
			(layer "F.Fab")
		)
		(fp_line
			(start 1.1938 -0.406654)
			(end 1.1938 0.4064)
			(stroke
				(width 0.1)
				(type default)
			)
			(layer "F.Fab")
		)
		(fp_line
			(start 1.1938 0.4064)
			(end 0.8636 0.4064)
			(stroke
				(width 0.1)
				(type default)
			)
			(layer "F.Fab")
		)
		(pad "1" smd rect
			(at -0.7366 0 270)
			(size 0.7112 0.8128)
			(layers "F.Cu" "F.Mask" "F.Paste")
			(net "P52V_HS2_SENSE_N_R2")
		)
		(pad "2" smd rect
			(at 0.7366 0 270)
			(size 0.7112 0.8128)
			(layers "F.Cu" "F.Mask" "F.Paste")
			(net "P52V_HS2_4287_ADC_N")
		)
	)
	(footprint ""
		(layer "F.Cu")
		(at 145.11782 -69.977)
		(property "Reference" "PR6983"
			(at 0 0 0)
			(layer "F.SilkS")
			(hide yes)
			(effects
				(font
					(size 1.27 1.27)
				)
			)
		)
		(property "Value" ""
			(at 0 0 0)
			(layer "F.Fab")
			(effects
				(font
					(size 1.27 1.27)
				)
			)
		)
		(duplicate_pad_numbers_are_jumpers no)
		(fp_line
			(start -1.2954 -0.5842)
			(end 1.2954 -0.5842)
			(stroke
				(width 0.1524)
				(type default)
			)
			(layer "F.SilkS")
		)
		(fp_line
			(start -1.2954 0.5842)
			(end -1.2954 -0.5842)
			(stroke
				(width 0.1524)
				(type default)
			)
			(layer "F.SilkS")
		)
		(fp_line
			(start 1.2954 -0.5842)
			(end 1.2954 0.5842)
			(stroke
				(width 0.1524)
				(type default)
			)
			(layer "F.SilkS")
		)
		(fp_line
			(start 1.2954 0.5842)
			(end -1.2954 0.5842)
			(stroke
				(width 0.1524)
				(type default)
			)
			(layer "F.SilkS")
		)
		(fp_line
			(start -1.1938 -0.406654)
			(end -0.8636 -0.406654)
			(stroke
				(width 0.1)
				(type default)
			)
			(layer "F.Fab")
		)
		(fp_line
			(start -1.1938 0.4064)
			(end -1.1938 -0.406654)
			(stroke
				(width 0.1)
				(type default)
			)
			(layer "F.Fab")
		)
		(fp_line
			(start -0.8636 -0.4572)
			(end 0.8636 -0.4572)
			(stroke
				(width 0.1)
				(type default)
			)
			(layer "F.Fab")
		)
		(fp_line
			(start -0.8636 -0.406654)
			(end -0.8636 -0.4572)
			(stroke
				(width 0.1)
				(type default)
			)
			(layer "F.Fab")
		)
		(fp_line
			(start -0.8636 0.4064)
			(end -1.1938 0.4064)
			(stroke
				(width 0.1)
				(type default)
			)
			(layer "F.Fab")
		)
		(fp_line
			(start -0.8636 0.4318)
			(end -0.8636 0.4064)
			(stroke
				(width 0.1)
				(type default)
			)
			(layer "F.Fab")
		)
		(fp_line
			(start -0.8636 0.4572)
			(end -0.8636 0.4318)
			(stroke
				(width 0.1)
				(type default)
			)
			(layer "F.Fab")
		)
		(fp_line
			(start 0.8636 -0.4572)
			(end 0.8636 -0.406654)
			(stroke
				(width 0.1)
				(type default)
			)
			(layer "F.Fab")
		)
		(fp_line
			(start 0.8636 -0.406654)
			(end 1.1938 -0.406654)
			(stroke
				(width 0.1)
				(type default)
			)
			(layer "F.Fab")
		)
		(fp_line
			(start 0.8636 0.4064)
			(end 0.8636 0.4572)
			(stroke
				(width 0.1)
				(type default)
			)
			(layer "F.Fab")
		)
		(fp_line
			(start 0.8636 0.4572)
			(end -0.8636 0.4572)
			(stroke
				(width 0.1)
				(type default)
			)
			(layer "F.Fab")
		)
		(fp_line
			(start 1.1938 -0.406654)
			(end 1.1938 0.4064)
			(stroke
				(width 0.1)
				(type default)
			)
			(layer "F.Fab")
		)
		(fp_line
			(start 1.1938 0.4064)
			(end 0.8636 0.4064)
			(stroke
				(width 0.1)
				(type default)
			)
			(layer "F.Fab")
		)
		(pad "1" smd rect
			(at -0.7366 0 270)
			(size 0.7112 0.8128)
			(layers "F.Cu" "F.Mask" "F.Paste")
			(net "P52V_HS2_4287_ADC_P")
		)
		(pad "2" smd rect
			(at 0.7366 0 270)
			(size 0.7112 0.8128)
			(layers "F.Cu" "F.Mask" "F.Paste")
			(net "P52V_HS2_SENSE_P_R1")
		)
	)
	(footprint ""
		(layer "F.Cu")
		(at 423.291 -47.371)
		(property "Reference" "C8"
			(at 0 0 0)
			(layer "F.SilkS")
			(hide yes)
			(effects
				(font
					(size 1.27 1.27)
				)
			)
		)
		(property "Value" ""
			(at 0 0 0)
			(layer "F.Fab")
			(effects
				(font
					(size 1.27 1.27)
				)
			)
		)
		(duplicate_pad_numbers_are_jumpers no)
		(fp_line
			(start -0.7874 -0.4064)
			(end 0.7874 -0.4064)
			(stroke
				(width 0.1524)
				(type default)
			)
			(layer "F.SilkS")
		)
		(fp_line
			(start -0.7874 0.4064)
			(end -0.7874 -0.4064)
			(stroke
				(width 0.1524)
				(type default)
			)
			(layer "F.SilkS")
		)
		(fp_line
			(start 0.7874 -0.4064)
			(end 0.7874 0.4064)
			(stroke
				(width 0.1524)
				(type default)
			)
			(layer "F.SilkS")
		)
		(fp_line
			(start 0.7874 0.4064)
			(end -0.7874 0.4064)
			(stroke
				(width 0.1524)
				(type default)
			)
			(layer "F.SilkS")
		)
		(fp_line
			(start -0.67945 -0.305054)
			(end -0.12065 -0.305054)
			(stroke
				(width 0.1)
				(type default)
			)
			(layer "F.Fab")
		)
		(fp_line
			(start -0.67945 0.3048)
			(end -0.67945 -0.305054)
			(stroke
				(width 0.1)
				(type default)
			)
			(layer "F.Fab")
		)
		(fp_line
			(start -0.12065 -0.305054)
			(end -0.12065 -0.2794)
			(stroke
				(width 0.1)
				(type default)
			)
			(layer "F.Fab")
		)
		(fp_line
			(start -0.12065 -0.2794)
			(end 0.12065 -0.2794)
			(stroke
				(width 0.1)
				(type default)
			)
			(layer "F.Fab")
		)
		(fp_line
			(start -0.12065 0.2794)
			(end -0.12065 0.3048)
			(stroke
				(width 0.1)
				(type default)
			)
			(layer "F.Fab")
		)
		(fp_line
			(start -0.12065 0.3048)
			(end -0.67945 0.3048)
			(stroke
				(width 0.1)
				(type default)
			)
			(layer "F.Fab")
		)
		(fp_line
			(start 0.120396 0.2794)
			(end -0.12065 0.2794)
			(stroke
				(width 0.1)
				(type default)
			)
			(layer "F.Fab")
		)
		(fp_line
			(start 0.120396 0.3048)
			(end 0.120396 0.2794)
			(stroke
				(width 0.1)
				(type default)
			)
			(layer "F.Fab")
		)
		(fp_line
			(start 0.12065 -0.3048)
			(end 0.67945 -0.3048)
			(stroke
				(width 0.1)
				(type default)
			)
			(layer "F.Fab")
		)
		(fp_line
			(start 0.12065 -0.2794)
			(end 0.12065 -0.3048)
			(stroke
				(width 0.1)
				(type default)
			)
			(layer "F.Fab")
		)
		(fp_line
			(start 0.67945 -0.3048)
			(end 0.67945 0.3048)
			(stroke
				(width 0.1)
				(type default)
			)
			(layer "F.Fab")
		)
		(fp_line
			(start 0.67945 0.3048)
			(end 0.120396 0.3048)
			(stroke
				(width 0.1)
				(type default)
			)
			(layer "F.Fab")
		)
		(pad "1" smd circle
			(at -0.40005 0)
			(size 0 0)
			(layers "F.Cu" "F.Mask" "F.Paste")
			(net "P3V3_AUX")
		)
		(pad "2" smd circle
			(at 0.40005 0)
			(size 0 0)
			(layers "F.Cu" "F.Mask" "F.Paste")
			(net "GND")
		)
	)
	(footprint ""
		(layer "F.Cu")
		(at 456.999848 -121.499884 180)
		(property "Reference" "H15"
			(at 0.917448 -5.448554 0)
			(unlocked yes)
			(layer "F.SilkS")
			(effects
				(font
					(size 0.7874 0.5842)
					(thickness 0.1524)
				)
				(justify left)
			)
		)
		(property "Value" ""
			(at 0 0 180)
			(layer "F.Fab")
			(effects
				(font
					(size 1.27 1.27)
				)
			)
		)
		(duplicate_pad_numbers_are_jumpers no)
		(pad "1" thru_hole oval
			(at 0 0 180)
			(size 9.017 14.0208)
			(drill 3.0226
				(offset 0 2.499868)
			)
			(layers "*.Cu" "*.Mask")
			(remove_unused_layers no)
			(net "GND")
			(clearance -1.500378)
			(padstack
				(mode front_inner_back)
				(layer "Inner"
					(shape circle)
					(size 0 0)
					(clearance 0)
				)
				(layer "B.Cu"
					(shape oval)
					(size 9.017 14.0208)
					(offset 0 2.499868)
					(clearance -1.500378)
				)
			)
		)
	)
	(footprint ""
		(layer "F.Cu")
		(at 323.13626 -29.5402 180)
		(property "Reference" "PQ35"
			(at -9.628886 -3.917188 0)
			(unlocked yes)
			(layer "F.SilkS")
			(effects
				(font
					(size 0.7874 0.5842)
					(thickness 0.1524)
				)
				(justify left)
			)
		)
		(property "Value" ""
			(at 0 0 180)
			(layer "F.Fab")
			(effects
				(font
					(size 1.27 1.27)
				)
			)
		)
		(duplicate_pad_numbers_are_jumpers no)
		(fp_line
			(start 7.649972 4.99999)
			(end 7.649972 -4.99999)
			(stroke
				(width 0.1524)
				(type default)
			)
			(layer "F.SilkS")
		)
		(fp_line
			(start 7.649972 -4.99999)
			(end 7.630414 -4.99999)
			(stroke
				(width 0.1524)
				(type default)
			)
			(layer "F.SilkS")
		)
		(fp_line
			(start 7.630414 4.99999)
			(end 7.649972 4.99999)
			(stroke
				(width 0.1524)
				(type default)
			)
			(layer "F.SilkS")
		)
		(fp_line
			(start 5.115814 -4.99999)
			(end -7.649972 -4.99999)
			(stroke
				(width 0.1524)
				(type default)
			)
			(layer "F.SilkS")
		)
		(fp_line
			(start -7.649972 4.99999)
			(end 5.115814 4.99999)
			(stroke
				(width 0.1524)
				(type default)
			)
			(layer "F.SilkS")
		)
		(fp_line
			(start -7.649972 3.3274)
			(end -7.649972 4.99999)
			(stroke
				(width 0.1524)
				(type default)
			)
			(layer "F.SilkS")
		)
		(fp_line
			(start -7.649972 -1.7526)
			(end -7.649972 1.7526)
			(stroke
				(width 0.1524)
				(type default)
			)
			(layer "F.SilkS")
		)
		(fp_line
			(start -7.649972 -4.99999)
			(end -7.649972 -3.3274)
			(stroke
				(width 0.1524)
				(type default)
			)
			(layer "F.SilkS")
		)
		(fp_line
			(start 7.649972 4.99999)
			(end 7.649972 -4.99999)
			(stroke
				(width 0.1)
				(type default)
			)
			(layer "F.Fab")
		)
		(fp_line
			(start 7.649972 -4.99999)
			(end -7.649972 -4.99999)
			(stroke
				(width 0.1)
				(type default)
			)
			(layer "F.Fab")
		)
		(fp_line
			(start -7.649972 4.99999)
			(end 7.649972 4.99999)
			(stroke
				(width 0.1)
				(type default)
			)
			(layer "F.Fab")
		)
		(fp_line
			(start -7.649972 -4.99999)
			(end -7.649972 4.99999)
			(stroke
				(width 0.1)
				(type default)
			)
			(layer "F.Fab")
		)
		(pad "D" smd circle
			(at 2.15011 0 180)
			(size 0 0)
			(layers "F.Cu" "F.Mask" "F.Paste")
			(net "P52V_HS1_DRAIN_2")
		)
		(pad "G" smd rect
			(at -7.050024 -2.54 90)
			(size 1.3208 3.0988)
			(layers "F.Cu" "F.Mask" "F.Paste")
			(net "P52V_HS1_GATE4")
		)
		(pad "S" smd rect
			(at -7.050024 2.54 90)
			(size 1.3208 3.0988)
			(layers "F.Cu" "F.Mask" "F.Paste")
			(net "P52V_HS1")
		)
		(zone
			(layer "F.Cu")
			(hatch none 0.5)
			(connect_pads
				(clearance 0)
			)
			(min_thickness 0.25)
			(keepout
				(tracks not_allowed)
				(vias allowed)
				(pads allowed)
				(copperpour not_allowed)
				(footprints allowed)
			)
			(placement
				(enabled no)
				(sheetname "")
			)
			(fill
				(thermal_gap 0.5)
				(thermal_bridge_width 0.5)
				(island_removal_mode 0)
			)
			(polygon
				(pts
					(xy 317.95466 -24.5618) (xy 330.78166 -24.5618) (xy 330.78166 -26.289) (xy 328.57186 -26.289) (xy 328.57186 -27.7114)
					(xy 330.78166 -27.7114) (xy 330.78166 -31.369) (xy 328.57186 -31.369) (xy 328.57186 -32.7914) (xy 330.78166 -32.7914)
					(xy 330.78166 -34.5186) (xy 317.95466 -34.5186) (xy 317.95466 -33.3502) (xy 324.15226 -33.3502)
					(xy 324.15226 -25.7302) (xy 317.95466 -25.7302)
				)
			)
		)
	)
	(footprint ""
		(layer "F.Cu")
		(at 413.07258 -30.26156 180)
		(property "Reference" "R5922"
			(at 0 0 180)
			(layer "F.SilkS")
			(hide yes)
			(effects
				(font
					(size 1.27 1.27)
				)
			)
		)
		(property "Value" ""
			(at 0 0 180)
			(layer "F.Fab")
			(effects
				(font
					(size 1.27 1.27)
				)
			)
		)
		(duplicate_pad_numbers_are_jumpers no)
		(fp_line
			(start 0.7874 0.4064)
			(end -0.7874 0.4064)
			(stroke
				(width 0.1524)
				(type default)
			)
			(layer "F.SilkS")
		)
		(fp_line
			(start 0.7874 -0.4064)
			(end 0.7874 0.4064)
			(stroke
				(width 0.1524)
				(type default)
			)
			(layer "F.SilkS")
		)
		(fp_line
			(start -0.7874 0.4064)
			(end -0.7874 -0.4064)
			(stroke
				(width 0.1524)
				(type default)
			)
			(layer "F.SilkS")
		)
		(fp_line
			(start -0.7874 -0.4064)
			(end 0.7874 -0.4064)
			(stroke
				(width 0.1524)
				(type default)
			)
			(layer "F.SilkS")
		)
		(fp_line
			(start 0.67945 0.3048)
			(end 0.120396 0.3048)
			(stroke
				(width 0.1)
				(type default)
			)
			(layer "F.Fab")
		)
		(fp_line
			(start 0.67945 -0.3048)
			(end 0.67945 0.3048)
			(stroke
				(width 0.1)
				(type default)
			)
			(layer "F.Fab")
		)
		(fp_line
			(start 0.12065 -0.2794)
			(end 0.12065 -0.3048)
			(stroke
				(width 0.1)
				(type default)
			)
			(layer "F.Fab")
		)
		(fp_line
			(start 0.12065 -0.3048)
			(end 0.67945 -0.3048)
			(stroke
				(width 0.1)
				(type default)
			)
			(layer "F.Fab")
		)
		(fp_line
			(start 0.120396 0.3048)
			(end 0.120396 0.2794)
			(stroke
				(width 0.1)
				(type default)
			)
			(layer "F.Fab")
		)
		(fp_line
			(start 0.120396 0.2794)
			(end -0.12065 0.2794)
			(stroke
				(width 0.1)
				(type default)
			)
			(layer "F.Fab")
		)
		(fp_line
			(start -0.12065 0.3048)
			(end -0.67945 0.3048)
			(stroke
				(width 0.1)
				(type default)
			)
			(layer "F.Fab")
		)
		(fp_line
			(start -0.12065 0.2794)
			(end -0.12065 0.3048)
			(stroke
				(width 0.1)
				(type default)
			)
			(layer "F.Fab")
		)
		(fp_line
			(start -0.12065 -0.2794)
			(end 0.12065 -0.2794)
			(stroke
				(width 0.1)
				(type default)
			)
			(layer "F.Fab")
		)
		(fp_line
			(start -0.12065 -0.305054)
			(end -0.12065 -0.2794)
			(stroke
				(width 0.1)
				(type default)
			)
			(layer "F.Fab")
		)
		(fp_line
			(start -0.67945 0.3048)
			(end -0.67945 -0.305054)
			(stroke
				(width 0.1)
				(type default)
			)
			(layer "F.Fab")
		)
		(fp_line
			(start -0.67945 -0.305054)
			(end -0.12065 -0.305054)
			(stroke
				(width 0.1)
				(type default)
			)
			(layer "F.Fab")
		)
		(pad "1" smd circle
			(at -0.40005 0 180)
			(size 0 0)
			(layers "F.Cu" "F.Mask" "F.Paste")
			(net "P12V_LED_FLTB")
		)
		(pad "2" smd circle
			(at 0.40005 0 180)
			(size 0 0)
			(layers "F.Cu" "F.Mask" "F.Paste")
			(net "P3V3_AUX")
		)
	)
)
